# TIMECARD (Time Appliance Project (Time Card)) — schematic netlist excerpt (pin names and nets, part order shuffled) for the footprints in the layout excerpt that follows; sources: Cadence DE-HDL packaged netlist, KiCad conversion of R4006-B0001-02_R01.brd

R376  RESISTOR  100OHM 1%  pkg SMC_0402R_H016  page 26 : \1\ = FPGA_OUT_SMA3_LED_RED_N ; \2\ = UNNAMED_14_LED4PV14_I267_3
SP49  NULL  pkg DUMMY  page 34

(kicad_pcb
	(version 20260206)
	(generator "pcbnew")
	(generator_version "10.0")
	(general
		(thickness 1.6)
		(legacy_teardrops no)
	)
	(paper "A4")
	(title_block
		(title "timecard-production-celestica-r4006 — R4006-B0001-02_R01.brd")
		(comment 1 "Time Appliance Project (Time Card) / footprints 33-34 of 1113")
	)
	(layers
		(0 "F.Cu" signal "TOP")
		(4 "In1.Cu" signal "L02_GND1")
		(6 "In2.Cu" signal "L03_SIG1")
		(8 "In3.Cu" signal "L04_GND2")
		(10 "In4.Cu" signal "L05_VCC1")
		(12 "In5.Cu" signal "L06_VCC2")
		(14 "In6.Cu" signal "L07_GND3")
		(16 "In7.Cu" signal "L08_SIG2")
		(18 "In8.Cu" signal "L09_GND4")
		(2 "B.Cu" signal "BOTTOM")
		(9 "F.Adhes" user "F.Adhesive")
		(11 "B.Adhes" user "B.Adhesive")
		(13 "F.Paste" user "Package Geometry/Pastemask Top")
		(15 "B.Paste" user "Package Geometry/Pastemask Bottom")
		(5 "F.SilkS" user "Ref Des/Silkscreen Top")
		(7 "B.SilkS" user "Ref Des/Silkscreen Bottom")
		(1 "F.Mask" user "Board Geometry/Soldermask Top")
		(3 "B.Mask" user "Board Geometry/Soldermask Bottom")
		(17 "Dwgs.User" user "User.Drawings")
		(19 "Cmts.User" user "User.Comments")
		(21 "Eco1.User" user "User.Eco1")
		(23 "Eco2.User" user "User.Eco2")
		(25 "Edge.Cuts" user "Board Geometry/Outline")
		(27 "Margin" user)
		(31 "F.CrtYd" user "Package Geometry/Place Bound Top")
		(29 "B.CrtYd" user "Package Geometry/Place Bound Bottom")
		(35 "F.Fab" user "Ref Des/Assembly Top")
		(33 "B.Fab" user "Ref Des/Assembly Bottom")
	)
	(footprint ""
		(layer "F.Cu")
		(at 7.2898 -68.201032 90)
		(property "Reference" "R376"
			(at 3.553968 -0.39243 90)
			(unlocked yes)
			(layer "F.SilkS")
			(effects
				(font
					(size 0.7874 0.5842)
					(thickness 0.1524)
				)
			)
		)
		(property "Value" "VAL*"
			(at 0.02032 2.13233 90)
			(unlocked yes)
			(layer "F.Fab")
			(hide yes)
			(effects
				(font
					(size 0.7874 0.5842)
					(thickness 0.1524)
				)
			)
		)
		(property "Device Type" "RESISTOR-G155-11000-01,100OHM,A"
			(at 0.008382 1.210564 90)
			(unlocked yes)
			(layer "F.Fab")
			(hide yes)
			(effects
				(font
					(size 0.7874 0.5842)
					(thickness 0.1524)
				)
			)
		)
		(property "User Part Number" "PARTNUM*"
			(at 0.02032 4.024884 90)
			(unlocked yes)
			(layer "Cmts.User")
			(hide yes)
			(effects
				(font
					(size 0.7874 0.5842)
					(thickness 0.1524)
				)
			)
		)
		(property "Tolerance" "TOL*"
			(at 0.044704 3.05435 90)
			(unlocked yes)
			(layer "Cmts.User")
			(hide yes)
			(effects
				(font
					(size 0.7874 0.5842)
					(thickness 0.1524)
				)
			)
		)
		(duplicate_pad_numbers_are_jumpers no)
		(fp_line
			(start 1.143 -0.5588)
			(end -1.143 -0.5588)
			(stroke
				(width 0.1)
				(type default)
			)
			(layer "F.SilkS")
		)
		(fp_line
			(start -1.143 -0.5588)
			(end -1.143 0.5588)
			(stroke
				(width 0.1)
				(type default)
			)
			(layer "F.SilkS")
		)
		(fp_line
			(start 1.143 0.5588)
			(end 1.143 -0.5588)
			(stroke
				(width 0.1)
				(type default)
			)
			(layer "F.SilkS")
		)
		(fp_line
			(start -1.143 0.5588)
			(end 1.143 0.5588)
			(stroke
				(width 0.1)
				(type default)
			)
			(layer "F.SilkS")
		)
		(fp_poly
			(pts
				(xy -1.143 0.5588) (xy 1.143 0.5588) (xy 1.143 -0.5588) (xy -1.143 -0.5588)
			)
			(stroke
				(width 0)
				(type default)
			)
			(fill no)
			(layer "F.CrtYd")
		)
		(fp_line
			(start 0.508 -0.3048)
			(end -0.508 -0.3048)
			(stroke
				(width 0.1)
				(type default)
			)
			(layer "F.Fab")
		)
		(fp_line
			(start -0.508 -0.3048)
			(end -0.508 0.3048)
			(stroke
				(width 0.1)
				(type default)
			)
			(layer "F.Fab")
		)
		(fp_line
			(start 0.508 0.3048)
			(end 0.508 -0.3048)
			(stroke
				(width 0.1)
				(type default)
			)
			(layer "F.Fab")
		)
		(fp_line
			(start -0.508 0.3048)
			(end 0.508 0.3048)
			(stroke
				(width 0.1)
				(type default)
			)
			(layer "F.Fab")
		)
		(pad "1" smd rect
			(at -0.5334 0 90)
			(size 0.7112 0.6096)
			(layers "F.Cu" "F.Mask" "F.Paste")
			(net "FPGA_OUT_SMA3_LED_RED_N")
		)
		(pad "2" smd rect
			(at 0.5334 0 90)
			(size 0.7112 0.6096)
			(layers "F.Cu" "F.Mask" "F.Paste")
			(net "UNNAMED_14_LED4PV14_I267_3")
		)
		(zone
			(layer "F.Cu")
			(hatch none 0.5)
			(connect_pads
				(clearance 0)
			)
			(min_thickness 0.25)
			(keepout
				(tracks not_allowed)
				(vias allowed)
				(pads allowed)
				(copperpour not_allowed)
				(footprints allowed)
			)
			(placement
				(enabled no)
				(sheetname "")
			)
			(fill
				(thermal_gap 0.5)
				(thermal_bridge_width 0.5)
				(island_removal_mode 0)
			)
			(polygon
				(pts
					(xy 7.5946 -68.124832) (xy 7.5946 -68.277232) (xy 6.985 -68.277232) (xy 6.985 -68.124832)
				)
			)
		)
		(zone
			(layer "F.Cu")
			(hatch none 0.5)
			(connect_pads
				(clearance 0)
			)
			(min_thickness 0.25)
			(keepout
				(tracks allowed)
				(vias not_allowed)
				(pads allowed)
				(copperpour not_allowed)
				(footprints allowed)
			)
			(placement
				(enabled no)
				(sheetname "")
			)
			(fill
				(thermal_gap 0.5)
				(thermal_bridge_width 0.5)
				(island_removal_mode 0)
			)
			(polygon
				(pts
					(xy 7.5946 -68.124832) (xy 7.5946 -68.277232) (xy 6.985 -68.277232) (xy 6.985 -68.124832)
				)
			)
		)
	)
	(footprint ""
		(layer "F.Cu")
		(at 66.04 -126.873)
		(property "Reference" "SP49"
			(at 0 0 0)
			(layer "F.SilkS")
			(hide yes)
			(effects
				(font
					(size 1.27 1.27)
				)
			)
		)
		(property "Value" ""
			(at 0 0 0)
			(layer "F.Fab")
			(effects
				(font
					(size 1.27 1.27)
				)
			)
		)
		(duplicate_pad_numbers_are_jumpers no)
	)
)
